# S9S_MB_2U (Grand Teton) — schematic netlist excerpt (pin names and nets, part order shuffled) for the footprints in the layout excerpt that follows; sources: Cadence DE-HDL packaged netlist, KiCad conversion of 03242023_DA0F0TMBIJ0_F0T_Motherboard_J_brd_V01_OCP.brd

PR3839  Q_RES  10K 1% CHIP  pkg 0402LF  page 157 : A = P12V_OCP_FLTB_1 ; B = P3V3_AUX
R3041  Q_RES  10K 1% CHIP  pkg 0402LF  page 204 : A = P3V3_AUX ; B = FM_PCH_GLB_RST_WARN_N

(kicad_pcb
	(version 20260206)
	(generator "pcbnew")
	(generator_version "10.0")
	(general
		(thickness 1.6)
		(legacy_teardrops no)
	)
	(paper "A4")
	(title_block
		(title "03242023_DA0F0TMBIJ0_F0T_Motherboard_J_brd_V01_OCP.brd")
		(comment 1 "Grand Teton / footprints 3743-3744 of 6105")
	)
	(layers
		(0 "F.Cu" signal "TOP")
		(4 "In1.Cu" signal "GND")
		(6 "In2.Cu" signal "IN1")
		(8 "In3.Cu" signal "GND1")
		(10 "In4.Cu" signal "IN2")
		(12 "In5.Cu" signal "GND2")
		(14 "In6.Cu" signal "IN3")
		(16 "In7.Cu" signal "GND3")
		(18 "In8.Cu" signal "VCC")
		(20 "In9.Cu" signal "VCC1")
		(22 "In10.Cu" signal "GND4")
		(24 "In11.Cu" signal "IN4")
		(26 "In12.Cu" signal "GND5")
		(28 "In13.Cu" signal "IN5")
		(30 "In14.Cu" signal "GND6")
		(32 "In15.Cu" signal "IN6")
		(34 "In16.Cu" signal "GND7")
		(2 "B.Cu" signal "BOTTOM")
		(9 "F.Adhes" user "F.Adhesive")
		(11 "B.Adhes" user "B.Adhesive")
		(13 "F.Paste" user "Package Geometry/Pastemask Top")
		(15 "B.Paste" user "Package Geometry/Pastemask Bottom")
		(5 "F.SilkS" user "Ref Des/Silkscreen Top")
		(7 "B.SilkS" user "Ref Des/Silkscreen Bottom")
		(1 "F.Mask" user "Board Geometry/Soldermask Top")
		(3 "B.Mask" user "Board Geometry/Soldermask Bottom")
		(17 "Dwgs.User" user "User.Drawings")
		(19 "Cmts.User" user "User.Comments")
		(21 "Eco1.User" user "User.Eco1")
		(23 "Eco2.User" user "User.Eco2")
		(25 "Edge.Cuts" user "Board Geometry/Outline")
		(27 "Margin" user)
		(31 "F.CrtYd" user "Package Geometry/Place Bound Top")
		(29 "B.CrtYd" user "Package Geometry/Place Bound Bottom")
		(35 "F.Fab" user "Ref Des/Assembly Top")
		(33 "B.Fab" user "Ref Des/Assembly Bottom")
	)
	(footprint ""
		(layer "F.Cu")
		(at 437.875172 -29.684218 180)
		(property "Reference" "PR3839"
			(at 0 0 180)
			(layer "F.SilkS")
			(hide yes)
			(effects
				(font
					(size 1.27 1.27)
				)
			)
		)
		(property "Value" ""
			(at 0 0 180)
			(layer "F.Fab")
			(effects
				(font
					(size 1.27 1.27)
				)
			)
		)
		(duplicate_pad_numbers_are_jumpers no)
		(fp_line
			(start 0.7874 0.4064)
			(end -0.7874 0.4064)
			(stroke
				(width 0.1524)
				(type default)
			)
			(layer "F.SilkS")
		)
		(fp_line
			(start 0.7874 -0.4064)
			(end 0.7874 0.4064)
			(stroke
				(width 0.1524)
				(type default)
			)
			(layer "F.SilkS")
		)
		(fp_line
			(start -0.7874 0.4064)
			(end -0.7874 -0.4064)
			(stroke
				(width 0.1524)
				(type default)
			)
			(layer "F.SilkS")
		)
		(fp_line
			(start -0.7874 -0.4064)
			(end 0.7874 -0.4064)
			(stroke
				(width 0.1524)
				(type default)
			)
			(layer "F.SilkS")
		)
		(fp_line
			(start 0.67945 0.3048)
			(end 0.120396 0.3048)
			(stroke
				(width 0.1)
				(type default)
			)
			(layer "F.Fab")
		)
		(fp_line
			(start 0.67945 -0.3048)
			(end 0.67945 0.3048)
			(stroke
				(width 0.1)
				(type default)
			)
			(layer "F.Fab")
		)
		(fp_line
			(start 0.12065 -0.2794)
			(end 0.12065 -0.3048)
			(stroke
				(width 0.1)
				(type default)
			)
			(layer "F.Fab")
		)
		(fp_line
			(start 0.12065 -0.3048)
			(end 0.67945 -0.3048)
			(stroke
				(width 0.1)
				(type default)
			)
			(layer "F.Fab")
		)
		(fp_line
			(start 0.120396 0.3048)
			(end 0.120396 0.2794)
			(stroke
				(width 0.1)
				(type default)
			)
			(layer "F.Fab")
		)
		(fp_line
			(start 0.120396 0.2794)
			(end -0.12065 0.2794)
			(stroke
				(width 0.1)
				(type default)
			)
			(layer "F.Fab")
		)
		(fp_line
			(start -0.12065 0.3048)
			(end -0.67945 0.3048)
			(stroke
				(width 0.1)
				(type default)
			)
			(layer "F.Fab")
		)
		(fp_line
			(start -0.12065 0.2794)
			(end -0.12065 0.3048)
			(stroke
				(width 0.1)
				(type default)
			)
			(layer "F.Fab")
		)
		(fp_line
			(start -0.12065 -0.2794)
			(end 0.12065 -0.2794)
			(stroke
				(width 0.1)
				(type default)
			)
			(layer "F.Fab")
		)
		(fp_line
			(start -0.12065 -0.305054)
			(end -0.12065 -0.2794)
			(stroke
				(width 0.1)
				(type default)
			)
			(layer "F.Fab")
		)
		(fp_line
			(start -0.67945 0.3048)
			(end -0.67945 -0.305054)
			(stroke
				(width 0.1)
				(type default)
			)
			(layer "F.Fab")
		)
		(fp_line
			(start -0.67945 -0.305054)
			(end -0.12065 -0.305054)
			(stroke
				(width 0.1)
				(type default)
			)
			(layer "F.Fab")
		)
		(pad "1" smd circle
			(at -0.40005 0 180)
			(size 0 0)
			(layers "F.Cu" "F.Mask" "F.Paste")
			(net "P12V_OCP_FLTB_1")
		)
		(pad "2" smd circle
			(at 0.40005 0 180)
			(size 0 0)
			(layers "F.Cu" "F.Mask" "F.Paste")
			(net "P3V3_AUX")
		)
	)
	(footprint ""
		(layer "F.Cu")
		(at 317.396622 -51.196748)
		(property "Reference" "R3041"
			(at 0 0 0)
			(layer "F.SilkS")
			(hide yes)
			(effects
				(font
					(size 1.27 1.27)
				)
			)
		)
		(property "Value" ""
			(at 0 0 0)
			(layer "F.Fab")
			(effects
				(font
					(size 1.27 1.27)
				)
			)
		)
		(duplicate_pad_numbers_are_jumpers no)
		(fp_line
			(start -0.7874 -0.4064)
			(end 0.7874 -0.4064)
			(stroke
				(width 0.1524)
				(type default)
			)
			(layer "F.SilkS")
		)
		(fp_line
			(start -0.7874 0.4064)
			(end -0.7874 -0.4064)
			(stroke
				(width 0.1524)
				(type default)
			)
			(layer "F.SilkS")
		)
		(fp_line
			(start 0.7874 -0.4064)
			(end 0.7874 0.4064)
			(stroke
				(width 0.1524)
				(type default)
			)
			(layer "F.SilkS")
		)
		(fp_line
			(start 0.7874 0.4064)
			(end -0.7874 0.4064)
			(stroke
				(width 0.1524)
				(type default)
			)
			(layer "F.SilkS")
		)
		(fp_line
			(start -0.67945 -0.305054)
			(end -0.12065 -0.305054)
			(stroke
				(width 0.1)
				(type default)
			)
			(layer "F.Fab")
		)
		(fp_line
			(start -0.67945 0.3048)
			(end -0.67945 -0.305054)
			(stroke
				(width 0.1)
				(type default)
			)
			(layer "F.Fab")
		)
		(fp_line
			(start -0.12065 -0.305054)
			(end -0.12065 -0.2794)
			(stroke
				(width 0.1)
				(type default)
			)
			(layer "F.Fab")
		)
		(fp_line
			(start -0.12065 -0.2794)
			(end 0.12065 -0.2794)
			(stroke
				(width 0.1)
				(type default)
			)
			(layer "F.Fab")
		)
		(fp_line
			(start -0.12065 0.2794)
			(end -0.12065 0.3048)
			(stroke
				(width 0.1)
				(type default)
			)
			(layer "F.Fab")
		)
		(fp_line
			(start -0.12065 0.3048)
			(end -0.67945 0.3048)
			(stroke
				(width 0.1)
				(type default)
			)
			(layer "F.Fab")
		)
		(fp_line
			(start 0.120396 0.2794)
			(end -0.12065 0.2794)
			(stroke
				(width 0.1)
				(type default)
			)
			(layer "F.Fab")
		)
		(fp_line
			(start 0.120396 0.3048)
			(end 0.120396 0.2794)
			(stroke
				(width 0.1)
				(type default)
			)
			(layer "F.Fab")
		)
		(fp_line
			(start 0.12065 -0.3048)
			(end 0.67945 -0.3048)
			(stroke
				(width 0.1)
				(type default)
			)
			(layer "F.Fab")
		)
		(fp_line
			(start 0.12065 -0.2794)
			(end 0.12065 -0.3048)
			(stroke
				(width 0.1)
				(type default)
			)
			(layer "F.Fab")
		)
		(fp_line
			(start 0.67945 -0.3048)
			(end 0.67945 0.3048)
			(stroke
				(width 0.1)
				(type default)
			)
			(layer "F.Fab")
		)
		(fp_line
			(start 0.67945 0.3048)
			(end 0.120396 0.3048)
			(stroke
				(width 0.1)
				(type default)
			)
			(layer "F.Fab")
		)
		(pad "1" smd circle
			(at -0.40005 0)
			(size 0 0)
			(layers "F.Cu" "F.Mask" "F.Paste")
			(net "P3V3_AUX")
		)
		(pad "2" smd circle
			(at 0.40005 0)
			(size 0 0)
			(layers "F.Cu" "F.Mask" "F.Paste")
			(net "FM_PCH_GLB_RST_WARN_N")
		)
	)
)
